(kicad_pcb
	(version 20260206)
	(generator "pcbnew")
	(generator_version "10.0")
	(general
		(thickness 1.6)
		(legacy_teardrops no)
	)
	(paper "A4")
	(title_block
		(title "12092022_DA0F0TFB6D0_F0T_FAN_BOARD_MP5048_D_brd_v02_OCP.brd")
		(comment 1 "Grand Teton / footprints 620-625 of 924")
	)
	(layers
		(0 "F.Cu" signal "TOP")
		(4 "In1.Cu" signal "GND")
		(6 "In2.Cu" signal "IN1")
		(8 "In3.Cu" signal "IN2")
		(10 "In4.Cu" signal "GND1")
		(2 "B.Cu" signal "BOTTOM")
		(9 "F.Adhes" user "F.Adhesive")
		(11 "B.Adhes" user "B.Adhesive")
		(13 "F.Paste" user "Package Geometry/Pastemask Top")
		(15 "B.Paste" user "Package Geometry/Pastemask Bottom")
		(5 "F.SilkS" user "Ref Des/Silkscreen Top")
		(7 "B.SilkS" user "Ref Des/Silkscreen Bottom")
		(1 "F.Mask" user "Board Geometry/Soldermask Top")
		(3 "B.Mask" user "Board Geometry/Soldermask Bottom")
		(17 "Dwgs.User" user "User.Drawings")
		(19 "Cmts.User" user "User.Comments")
		(21 "Eco1.User" user "User.Eco1")
		(23 "Eco2.User" user "User.Eco2")
		(25 "Edge.Cuts" user "Board Geometry/Outline")
		(27 "Margin" user)
		(31 "F.CrtYd" user "Package Geometry/Place Bound Top")
		(29 "B.CrtYd" user "Package Geometry/Place Bound Bottom")
		(35 "F.Fab" user "Ref Des/Assembly Top")
		(33 "B.Fab" user "Ref Des/Assembly Bottom")
	)
	(footprint ""
		(layer "F.Cu")
		(at 20.5486 -160.02 -90)
		(property "Reference" "R5470"
			(at 0 0 270)
			(layer "F.SilkS")
			(hide yes)
			(effects
				(font
					(size 1.27 1.27)
				)
			)
		)
		(property "Value" ""
			(at 0 0 270)
			(layer "F.Fab")
			(effects
				(font
					(size 1.27 1.27)
				)
			)
		)
		(duplicate_pad_numbers_are_jumpers no)
		(fp_line
			(start -0.7874 0.4064)
			(end -0.7874 -0.4064)
			(stroke
				(width 0.1524)
				(type default)
			)
			(layer "F.SilkS")
		)
		(fp_line
			(start 0.7874 0.4064)
			(end -0.7874 0.4064)
			(stroke
				(width 0.1524)
				(type default)
			)
			(layer "F.SilkS")
		)
		(fp_line
			(start -0.7874 -0.4064)
			(end 0.7874 -0.4064)
			(stroke
				(width 0.1524)
				(type default)
			)
			(layer "F.SilkS")
		)
		(fp_line
			(start 0.7874 -0.4064)
			(end 0.7874 0.4064)
			(stroke
				(width 0.1524)
				(type default)
			)
			(layer "F.SilkS")
		)
		(fp_line
			(start -0.67945 0.3048)
			(end -0.67945 -0.305054)
			(stroke
				(width 0.1)
				(type default)
			)
			(layer "F.Fab")
		)
		(fp_line
			(start -0.12065 0.3048)
			(end -0.67945 0.3048)
			(stroke
				(width 0.1)
				(type default)
			)
			(layer "F.Fab")
		)
		(fp_line
			(start 0.120396 0.3048)
			(end 0.120396 0.2794)
			(stroke
				(width 0.1)
				(type default)
			)
			(layer "F.Fab")
		)
		(fp_line
			(start 0.67945 0.3048)
			(end 0.120396 0.3048)
			(stroke
				(width 0.1)
				(type default)
			)
			(layer "F.Fab")
		)
		(fp_line
			(start -0.12065 0.2794)
			(end -0.12065 0.3048)
			(stroke
				(width 0.1)
				(type default)
			)
			(layer "F.Fab")
		)
		(fp_line
			(start 0.120396 0.2794)
			(end -0.12065 0.2794)
			(stroke
				(width 0.1)
				(type default)
			)
			(layer "F.Fab")
		)
		(fp_line
			(start -0.12065 -0.2794)
			(end 0.12065 -0.2794)
			(stroke
				(width 0.1)
				(type default)
			)
			(layer "F.Fab")
		)
		(fp_line
			(start 0.12065 -0.2794)
			(end 0.12065 -0.3048)
			(stroke
				(width 0.1)
				(type default)
			)
			(layer "F.Fab")
		)
		(fp_line
			(start 0.12065 -0.3048)
			(end 0.67945 -0.3048)
			(stroke
				(width 0.1)
				(type default)
			)
			(layer "F.Fab")
		)
		(fp_line
			(start 0.67945 -0.3048)
			(end 0.67945 0.3048)
			(stroke
				(width 0.1)
				(type default)
			)
			(layer "F.Fab")
		)
		(fp_line
			(start -0.67945 -0.305054)
			(end -0.12065 -0.305054)
			(stroke
				(width 0.1)
				(type default)
			)
			(layer "F.Fab")
		)
		(fp_line
			(start -0.12065 -0.305054)
			(end -0.12065 -0.2794)
			(stroke
				(width 0.1)
				(type default)
			)
			(layer "F.Fab")
		)
		(pad "1" smd circle
			(at -0.40005 0 270)
			(size 0 0)
			(layers "F.Cu" "F.Mask" "F.Paste")
			(net "PD_TCA9548_SML1_U321_A2")
		)
		(pad "2" smd circle
			(at 0.40005 0 270)
			(size 0 0)
			(layers "F.Cu" "F.Mask" "F.Paste")
			(net "GND")
		)
	)
	(footprint ""
		(layer "F.Cu")
		(at 27.432 -179.451 180)
		(property "Reference" "R5489"
			(at 0 0 180)
			(layer "F.SilkS")
			(hide yes)
			(effects
				(font
					(size 1.27 1.27)
				)
			)
		)
		(property "Value" ""
			(at 0 0 180)
			(layer "F.Fab")
			(effects
				(font
					(size 1.27 1.27)
				)
			)
		)
		(duplicate_pad_numbers_are_jumpers no)
		(fp_line
			(start 0.7874 0.4064)
			(end -0.7874 0.4064)
			(stroke
				(width 0.1524)
				(type default)
			)
			(layer "F.SilkS")
		)
		(fp_line
			(start 0.7874 -0.4064)
			(end 0.7874 0.4064)
			(stroke
				(width 0.1524)
				(type default)
			)
			(layer "F.SilkS")
		)
		(fp_line
			(start -0.7874 0.4064)
			(end -0.7874 -0.4064)
			(stroke
				(width 0.1524)
				(type default)
			)
			(layer "F.SilkS")
		)
		(fp_line
			(start -0.7874 -0.4064)
			(end 0.7874 -0.4064)
			(stroke
				(width 0.1524)
				(type default)
			)
			(layer "F.SilkS")
		)
		(fp_line
			(start 0.67945 0.3048)
			(end 0.120396 0.3048)
			(stroke
				(width 0.1)
				(type default)
			)
			(layer "F.Fab")
		)
		(fp_line
			(start 0.67945 -0.3048)
			(end 0.67945 0.3048)
			(stroke
				(width 0.1)
				(type default)
			)
			(layer "F.Fab")
		)
		(fp_line
			(start 0.12065 -0.2794)
			(end 0.12065 -0.3048)
			(stroke
				(width 0.1)
				(type default)
			)
			(layer "F.Fab")
		)
		(fp_line
			(start 0.12065 -0.3048)
			(end 0.67945 -0.3048)
			(stroke
				(width 0.1)
				(type default)
			)
			(layer "F.Fab")
		)
		(fp_line
			(start 0.120396 0.3048)
			(end 0.120396 0.2794)
			(stroke
				(width 0.1)
				(type default)
			)
			(layer "F.Fab")
		)
		(fp_line
			(start 0.120396 0.2794)
			(end -0.12065 0.2794)
			(stroke
				(width 0.1)
				(type default)
			)
			(layer "F.Fab")
		)
		(fp_line
			(start -0.12065 0.3048)
			(end -0.67945 0.3048)
			(stroke
				(width 0.1)
				(type default)
			)
			(layer "F.Fab")
		)
		(fp_line
			(start -0.12065 0.2794)
			(end -0.12065 0.3048)
			(stroke
				(width 0.1)
				(type default)
			)
			(layer "F.Fab")
		)
		(fp_line
			(start -0.12065 -0.2794)
			(end 0.12065 -0.2794)
			(stroke
				(width 0.1)
				(type default)
			)
			(layer "F.Fab")
		)
		(fp_line
			(start -0.12065 -0.305054)
			(end -0.12065 -0.2794)
			(stroke
				(width 0.1)
				(type default)
			)
			(layer "F.Fab")
		)
		(fp_line
			(start -0.67945 0.3048)
			(end -0.67945 -0.305054)
			(stroke
				(width 0.1)
				(type default)
			)
			(layer "F.Fab")
		)
		(fp_line
			(start -0.67945 -0.305054)
			(end -0.12065 -0.305054)
			(stroke
				(width 0.1)
				(type default)
			)
			(layer "F.Fab")
		)
		(pad "1" smd circle
			(at -0.40005 0 180)
			(size 0 0)
			(layers "F.Cu" "F.Mask" "F.Paste")
			(net "P52V_FAN_2_BUFF_EN")
		)
		(pad "2" smd circle
			(at 0.40005 0 180)
			(size 0 0)
			(layers "F.Cu" "F.Mask" "F.Paste")
			(net "P52V_FAN_2_BUFF_EN_R")
		)
	)
	(footprint ""
		(layer "F.Cu")
		(at 23.495 -162.941 90)
		(property "Reference" "R5275"
			(at 0 0 90)
			(layer "F.SilkS")
			(hide yes)
			(effects
				(font
					(size 1.27 1.27)
				)
			)
		)
		(property "Value" ""
			(at 0 0 90)
			(layer "F.Fab")
			(effects
				(font
					(size 1.27 1.27)
				)
			)
		)
		(duplicate_pad_numbers_are_jumpers no)
		(fp_line
			(start 0.7874 -0.4064)
			(end 0.7874 0.4064)
			(stroke
				(width 0.1524)
				(type default)
			)
			(layer "F.SilkS")
		)
		(fp_line
			(start -0.7874 -0.4064)
			(end 0.7874 -0.4064)
			(stroke
				(width 0.1524)
				(type default)
			)
			(layer "F.SilkS")
		)
		(fp_line
			(start 0.7874 0.4064)
			(end -0.7874 0.4064)
			(stroke
				(width 0.1524)
				(type default)
			)
			(layer "F.SilkS")
		)
		(fp_line
			(start -0.7874 0.4064)
			(end -0.7874 -0.4064)
			(stroke
				(width 0.1524)
				(type default)
			)
			(layer "F.SilkS")
		)
		(fp_line
			(start -0.12065 -0.305054)
			(end -0.12065 -0.2794)
			(stroke
				(width 0.1)
				(type default)
			)
			(layer "F.Fab")
		)
		(fp_line
			(start -0.67945 -0.305054)
			(end -0.12065 -0.305054)
			(stroke
				(width 0.1)
				(type default)
			)
			(layer "F.Fab")
		)
		(fp_line
			(start 0.67945 -0.3048)
			(end 0.67945 0.3048)
			(stroke
				(width 0.1)
				(type default)
			)
			(layer "F.Fab")
		)
		(fp_line
			(start 0.12065 -0.3048)
			(end 0.67945 -0.3048)
			(stroke
				(width 0.1)
				(type default)
			)
			(layer "F.Fab")
		)
		(fp_line
			(start 0.12065 -0.2794)
			(end 0.12065 -0.3048)
			(stroke
				(width 0.1)
				(type default)
			)
			(layer "F.Fab")
		)
		(fp_line
			(start -0.12065 -0.2794)
			(end 0.12065 -0.2794)
			(stroke
				(width 0.1)
				(type default)
			)
			(layer "F.Fab")
		)
		(fp_line
			(start 0.120396 0.2794)
			(end -0.12065 0.2794)
			(stroke
				(width 0.1)
				(type default)
			)
			(layer "F.Fab")
		)
		(fp_line
			(start -0.12065 0.2794)
			(end -0.12065 0.3048)
			(stroke
				(width 0.1)
				(type default)
			)
			(layer "F.Fab")
		)
		(fp_line
			(start 0.67945 0.3048)
			(end 0.120396 0.3048)
			(stroke
				(width 0.1)
				(type default)
			)
			(layer "F.Fab")
		)
		(fp_line
			(start 0.120396 0.3048)
			(end 0.120396 0.2794)
			(stroke
				(width 0.1)
				(type default)
			)
			(layer "F.Fab")
		)
		(fp_line
			(start -0.12065 0.3048)
			(end -0.67945 0.3048)
			(stroke
				(width 0.1)
				(type default)
			)
			(layer "F.Fab")
		)
		(fp_line
			(start -0.67945 0.3048)
			(end -0.67945 -0.305054)
			(stroke
				(width 0.1)
				(type default)
			)
			(layer "F.Fab")
		)
		(pad "1" smd circle
			(at -0.40005 0 90)
			(size 0 0)
			(layers "F.Cu" "F.Mask" "F.Paste")
			(net "SMB_FAN7_R_SDA")
		)
		(pad "2" smd circle
			(at 0.40005 0 90)
			(size 0 0)
			(layers "F.Cu" "F.Mask" "F.Paste")
			(net "P3V3_AUX")
		)
	)
	(footprint ""
		(layer "F.Cu")
		(at 15.24 -216.027 180)
		(property "Reference" "Q15"
			(at 4.445 -1.29667 0)
			(unlocked yes)
			(layer "F.SilkS")
			(effects
				(font
					(size 0.7874 0.5842)
					(thickness 0.1524)
				)
				(justify left)
			)
		)
		(property "Value" ""
			(at 0 0 180)
			(layer "F.Fab")
			(effects
				(font
					(size 1.27 1.27)
				)
			)
		)
		(duplicate_pad_numbers_are_jumpers no)
		(fp_line
			(start 1.905 1.651)
			(end -1.905 1.651)
			(stroke
				(width 0.1524)
				(type default)
			)
			(layer "F.SilkS")
		)
		(fp_line
			(start 1.905 -1.651)
			(end 1.905 1.651)
			(stroke
				(width 0.1524)
				(type default)
			)
			(layer "F.SilkS")
		)
		(fp_line
			(start -1.905 1.651)
			(end -1.905 -1.651)
			(stroke
				(width 0.1524)
				(type default)
			)
			(layer "F.SilkS")
		)
		(fp_line
			(start -1.905 -1.651)
			(end 1.905 -1.651)
			(stroke
				(width 0.1524)
				(type default)
			)
			(layer "F.SilkS")
		)
		(fp_line
			(start 1.249934 0.219964)
			(end 0.6985 0.219964)
			(stroke
				(width 0.1)
				(type default)
			)
			(layer "F.Fab")
		)
		(fp_line
			(start 1.249934 -0.219964)
			(end 1.249934 0.219964)
			(stroke
				(width 0.1)
				(type default)
			)
			(layer "F.Fab")
		)
		(fp_line
			(start 0.6985 1.524)
			(end -0.6985 1.524)
			(stroke
				(width 0.1)
				(type default)
			)
			(layer "F.Fab")
		)
		(fp_line
			(start 0.6985 0.219964)
			(end 0.6985 1.524)
			(stroke
				(width 0.1)
				(type default)
			)
			(layer "F.Fab")
		)
		(fp_line
			(start 0.6985 -0.219964)
			(end 1.249934 -0.219964)
			(stroke
				(width 0.1)
				(type default)
			)
			(layer "F.Fab")
		)
		(fp_line
			(start 0.6985 -1.524)
			(end 0.6985 -0.219964)
			(stroke
				(width 0.1)
				(type default)
			)
			(layer "F.Fab")
		)
		(fp_line
			(start -0.6985 1.524)
			(end -0.6985 1.169924)
			(stroke
				(width 0.1)
				(type default)
			)
			(layer "F.Fab")
		)
		(fp_line
			(start -0.6985 1.169924)
			(end -1.249934 1.169924)
			(stroke
				(width 0.1)
				(type default)
			)
			(layer "F.Fab")
		)
		(fp_line
			(start -0.6985 0.729996)
			(end -0.6985 -0.729996)
			(stroke
				(width 0.1)
				(type default)
			)
			(layer "F.Fab")
		)
		(fp_line
			(start -0.6985 -0.729996)
			(end -1.249934 -0.729996)
			(stroke
				(width 0.1)
				(type default)
			)
			(layer "F.Fab")
		)
		(fp_line
			(start -0.6985 -1.169924)
			(end -0.6985 -1.524)
			(stroke
				(width 0.1)
				(type default)
			)
			(layer "F.Fab")
		)
		(fp_line
			(start -0.6985 -1.524)
			(end 0.6985 -1.524)
			(stroke
				(width 0.1)
				(type default)
			)
			(layer "F.Fab")
		)
		(fp_line
			(start -1.249934 1.169924)
			(end -1.249934 0.729996)
			(stroke
				(width 0.1)
				(type default)
			)
			(layer "F.Fab")
		)
		(fp_line
			(start -1.249934 0.729996)
			(end -0.6985 0.729996)
			(stroke
				(width 0.1)
				(type default)
			)
			(layer "F.Fab")
		)
		(fp_line
			(start -1.249934 -0.729996)
			(end -1.249934 -1.169924)
			(stroke
				(width 0.1)
				(type default)
			)
			(layer "F.Fab")
		)
		(fp_line
			(start -1.249934 -1.169924)
			(end -0.6985 -1.169924)
			(stroke
				(width 0.1)
				(type default)
			)
			(layer "F.Fab")
		)
		(fp_rect
			(start -0.6985 1.524)
			(end 0.6985 -1.524)
			(stroke
				(width 0)
				(type default)
			)
			(fill no)
			(layer "F.Fab")
		)
		(pad "D" smd rect
			(at 1.1176 0 90)
			(size 1.016 1.27)
			(layers "F.Cu" "F.Mask" "F.Paste")
			(net "P12V_LED_FAN6")
		)
		(pad "G" smd rect
			(at -1.1176 -1.016 90)
			(size 1.016 1.27)
			(layers "F.Cu" "F.Mask" "F.Paste")
			(net "U411_D1")
		)
		(pad "S" smd rect
			(at -1.1176 1.016 90)
			(size 1.016 1.27)
			(layers "F.Cu" "F.Mask" "F.Paste")
			(net "P12V_LED")
		)
	)
	(footprint ""
		(layer "F.Cu")
		(at 19.05 -16.002 180)
		(property "Reference" "R5308"
			(at 0 0 180)
			(layer "F.SilkS")
			(hide yes)
			(effects
				(font
					(size 1.27 1.27)
				)
			)
		)
		(property "Value" ""
			(at 0 0 180)
			(layer "F.Fab")
			(effects
				(font
					(size 1.27 1.27)
				)
			)
		)
		(duplicate_pad_numbers_are_jumpers no)
		(fp_line
			(start 1.2954 0.5842)
			(end -1.2954 0.5842)
			(stroke
				(width 0.1524)
				(type default)
			)
			(layer "F.SilkS")
		)
		(fp_line
			(start 1.2954 -0.5842)
			(end 1.2954 0.5842)
			(stroke
				(width 0.1524)
				(type default)
			)
			(layer "F.SilkS")
		)
		(fp_line
			(start -1.2954 0.5842)
			(end -1.2954 -0.5842)
			(stroke
				(width 0.1524)
				(type default)
			)
			(layer "F.SilkS")
		)
		(fp_line
			(start -1.2954 -0.5842)
			(end 1.2954 -0.5842)
			(stroke
				(width 0.1524)
				(type default)
			)
			(layer "F.SilkS")
		)
		(fp_line
			(start 1.1938 0.4064)
			(end 0.8636 0.4064)
			(stroke
				(width 0.1)
				(type default)
			)
			(layer "F.Fab")
		)
		(fp_line
			(start 1.1938 -0.406654)
			(end 1.1938 0.4064)
			(stroke
				(width 0.1)
				(type default)
			)
			(layer "F.Fab")
		)
		(fp_line
			(start 0.8636 0.4572)
			(end -0.8636 0.4572)
			(stroke
				(width 0.1)
				(type default)
			)
			(layer "F.Fab")
		)
		(fp_line
			(start 0.8636 0.4064)
			(end 0.8636 0.4572)
			(stroke
				(width 0.1)
				(type default)
			)
			(layer "F.Fab")
		)
		(fp_line
			(start 0.8636 -0.406654)
			(end 1.1938 -0.406654)
			(stroke
				(width 0.1)
				(type default)
			)
			(layer "F.Fab")
		)
		(fp_line
			(start 0.8636 -0.4572)
			(end 0.8636 -0.406654)
			(stroke
				(width 0.1)
				(type default)
			)
			(layer "F.Fab")
		)
		(fp_line
			(start -0.8636 0.4572)
			(end -0.8636 0.4318)
			(stroke
				(width 0.1)
				(type default)
			)
			(layer "F.Fab")
		)
		(fp_line
			(start -0.8636 0.4318)
			(end -0.8636 0.4064)
			(stroke
				(width 0.1)
				(type default)
			)
			(layer "F.Fab")
		)
		(fp_line
			(start -0.8636 0.4064)
			(end -1.1938 0.4064)
			(stroke
				(width 0.1)
				(type default)
			)
			(layer "F.Fab")
		)
		(fp_line
			(start -0.8636 -0.406654)
			(end -0.8636 -0.4572)
			(stroke
				(width 0.1)
				(type default)
			)
			(layer "F.Fab")
		)
		(fp_line
			(start -0.8636 -0.4572)
			(end 0.8636 -0.4572)
			(stroke
				(width 0.1)
				(type default)
			)
			(layer "F.Fab")
		)
		(fp_line
			(start -1.1938 0.4064)
			(end -1.1938 -0.406654)
			(stroke
				(width 0.1)
				(type default)
			)
			(layer "F.Fab")
		)
		(fp_line
			(start -1.1938 -0.406654)
			(end -0.8636 -0.406654)
			(stroke
				(width 0.1)
				(type default)
			)
			(layer "F.Fab")
		)
		(pad "1" smd rect
			(at -0.7366 0 90)
			(size 0.7112 0.8128)
			(layers "F.Cu" "F.Mask" "F.Paste")
			(net "P52V_FAN_4")
		)
		(pad "2" smd rect
			(at 0.7366 0 90)
			(size 0.7112 0.8128)
			(layers "F.Cu" "F.Mask" "F.Paste")
			(net "FAN_4_TACH_IL_R")
		)
	)
	(footprint ""
		(layer "F.Cu")
		(at 36.703 -107.061 90)
		(property "Reference" "R5404"
			(at 0 0 90)
			(layer "F.SilkS")
			(hide yes)
			(effects
				(font
					(size 1.27 1.27)
				)
			)
		)
		(property "Value" ""
			(at 0 0 90)
			(layer "F.Fab")
			(effects
				(font
					(size 1.27 1.27)
				)
			)
		)
		(duplicate_pad_numbers_are_jumpers no)
		(fp_line
			(start 0.7874 -0.4064)
			(end 0.7874 0.4064)
			(stroke
				(width 0.1524)
				(type default)
			)
			(layer "F.SilkS")
		)
		(fp_line
			(start -0.7874 -0.4064)
			(end 0.7874 -0.4064)
			(stroke
				(width 0.1524)
				(type default)
			)
			(layer "F.SilkS")
		)
		(fp_line
			(start 0.7874 0.4064)
			(end -0.7874 0.4064)
			(stroke
				(width 0.1524)
				(type default)
			)
			(layer "F.SilkS")
		)
		(fp_line
			(start -0.7874 0.4064)
			(end -0.7874 -0.4064)
			(stroke
				(width 0.1524)
				(type default)
			)
			(layer "F.SilkS")
		)
		(fp_line
			(start -0.12065 -0.305054)
			(end -0.12065 -0.2794)
			(stroke
				(width 0.1)
				(type default)
			)
			(layer "F.Fab")
		)
		(fp_line
			(start -0.67945 -0.305054)
			(end -0.12065 -0.305054)
			(stroke
				(width 0.1)
				(type default)
			)
			(layer "F.Fab")
		)
		(fp_line
			(start 0.67945 -0.3048)
			(end 0.67945 0.3048)
			(stroke
				(width 0.1)
				(type default)
			)
			(layer "F.Fab")
		)
		(fp_line
			(start 0.12065 -0.3048)
			(end 0.67945 -0.3048)
			(stroke
				(width 0.1)
				(type default)
			)
			(layer "F.Fab")
		)
		(fp_line
			(start 0.12065 -0.2794)
			(end 0.12065 -0.3048)
			(stroke
				(width 0.1)
				(type default)
			)
			(layer "F.Fab")
		)
		(fp_line
			(start -0.12065 -0.2794)
			(end 0.12065 -0.2794)
			(stroke
				(width 0.1)
				(type default)
			)
			(layer "F.Fab")
		)
		(fp_line
			(start 0.120396 0.2794)
			(end -0.12065 0.2794)
			(stroke
				(width 0.1)
				(type default)
			)
			(layer "F.Fab")
		)
		(fp_line
			(start -0.12065 0.2794)
			(end -0.12065 0.3048)
			(stroke
				(width 0.1)
				(type default)
			)
			(layer "F.Fab")
		)
		(fp_line
			(start 0.67945 0.3048)
			(end 0.120396 0.3048)
			(stroke
				(width 0.1)
				(type default)
			)
			(layer "F.Fab")
		)
		(fp_line
			(start 0.120396 0.3048)
			(end 0.120396 0.2794)
			(stroke
				(width 0.1)
				(type default)
			)
			(layer "F.Fab")
		)
		(fp_line
			(start -0.12065 0.3048)
			(end -0.67945 0.3048)
			(stroke
				(width 0.1)
				(type default)
			)
			(layer "F.Fab")
		)
		(fp_line
			(start -0.67945 0.3048)
			(end -0.67945 -0.305054)
			(stroke
				(width 0.1)
				(type default)
			)
			(layer "F.Fab")
		)
		(pad "1" smd rect
			(at -0.40005 0 270)
			(size 0.4572 0.508)
			(layers "F.Cu" "F.Mask" "F.Paste")
			(net "FAN_2_OK_LED_R_N")
		)
		(pad "2" smd rect
			(at 0.40005 0 270)
			(size 0.4572 0.508)
			(layers "F.Cu" "F.Mask" "F.Paste")
			(net "FAN_2_OK_R_LED_N")
		)
	)
)
